(kicad_pcb
	(version 20260206)
	(generator "pcbnew")
	(generator_version "10.0")
	(general
		(thickness 1.6)
		(legacy_teardrops no)
	)
	(paper "A4")
	(title_block
		(title "baseboard — 13948-1b.1110WZS1818.brd")
		(comment 1 "Honey Badger (Wiwynn) / footprint 1425 of 2523 (MEZCN1), pads 121-122 of 122")
	)
	(layers
		(0 "F.Cu" signal "TOP")
		(4 "In1.Cu" signal "L2GND")
		(6 "In2.Cu" signal "L3")
		(8 "In3.Cu" signal "L4VCC")
		(10 "In4.Cu" signal "L5VCC")
		(12 "In5.Cu" signal "L6")
		(14 "In6.Cu" signal "L7GND")
		(2 "B.Cu" signal "BOTTOM")
		(9 "F.Adhes" user "F.Adhesive")
		(11 "B.Adhes" user "B.Adhesive")
		(13 "F.Paste" user "Package Geometry/Pastemask Top")
		(15 "B.Paste" user "Package Geometry/Pastemask Bottom")
		(5 "F.SilkS" user "Ref Des/Silkscreen Top")
		(7 "B.SilkS" user "Ref Des/Silkscreen Bottom")
		(1 "F.Mask" user "Board Geometry/Soldermask Top")
		(3 "B.Mask" user "Board Geometry/Soldermask Bottom")
		(17 "Dwgs.User" user "User.Drawings")
		(19 "Cmts.User" user "User.Comments")
		(21 "Eco1.User" user "User.Eco1")
		(23 "Eco2.User" user "User.Eco2")
		(25 "Edge.Cuts" user "Board Geometry/Outline")
		(27 "Margin" user)
		(31 "F.CrtYd" user "Package Geometry/Place Bound Top")
		(29 "B.CrtYd" user "Package Geometry/Place Bound Bottom")
		(35 "F.Fab" user "Ref Des/Assembly Top")
		(33 "B.Fab" user "Ref Des/Assembly Bottom")
	)
	(footprint ""
		(layer "F.Cu")
		(at 310.900064 -72.00011 -90)
		(property "Reference" "MEZCN1"
			(at 0 0 270)
			(layer "F.SilkS")
			(hide yes)
			(effects
				(font
					(size 1.27 1.27)
				)
			)
		)
		(property "Value" "FCI-CONN120-GP"
			(at -29.345382 -6.235192 270)
			(unlocked yes)
			(layer "F.Fab")
			(hide yes)
			(effects
				(font
					(size 1.016 1.016)
					(thickness 0.1524)
				)
			)
		)
		(property "Device Type" "61082-121402LF-U"
			(at -29.345382 -7.759192 270)
			(unlocked yes)
			(layer "F.Fab")
			(hide yes)
			(effects
				(font
					(size 1.016 1.016)
					(thickness 0.1524)
				)
			)
		)
		(duplicate_pad_numbers_are_jumpers no)
		(pad "119" smd rect
			(at -22.800056 2.22504 270)
			(size 0.508 2.0574)
			(layers "F.Cu" "F.Mask" "F.Paste")
			(net "GND")
		)
		(pad "120" smd rect
			(at -23.599902 2.22504 270)
			(size 0.508 2.0574)
			(layers "F.Cu" "F.Mask" "F.Paste")
			(net "CONN_10G_PRSNT2_N")
		)
	)
)
